# T6G (Grand Teton) — schematic netlist excerpt (pin names and nets, part order shuffled) for the footprints in the layout excerpt that follows; sources: Cadence DE-HDL packaged netlist, KiCad conversion of 04192023_DAF0TMB3IC0_F0TG_MB_C_brd_V02_OCP.brd

C630  Q_CAP  22UF 4V 20% X6S  pkg C0402  page 290 : A = P0V9_CPU0_RT1_2A ; B = GND
R553  Q_RES  4.7K 5% CHIP  pkg 0402LF  page 55 : A = CPU1_NV_SAVE_N ; B = PVDD18_S5_P1
C6690  Q_CAP_DIFFBUS  DIFF BUS_0.22UF 6.3V 20% X6S  pkg C0201  page 330 : \1\ = P5E_CPU1_P1_TX_BUF_C_DN<14> ; \2\ = P5E_CPU1_P1_TX_BUF_DN<14>

(kicad_pcb
	(version 20260206)
	(generator "pcbnew")
	(generator_version "10.0")
	(general
		(thickness 1.6)
		(legacy_teardrops no)
	)
	(paper "A4")
	(title_block
		(title "04192023_DAF0TMB3IC0_F0TG_MB_C_brd_V02_OCP.brd")
		(comment 1 "Grand Teton / footprints 5596-5598 of 8354")
	)
	(layers
		(0 "F.Cu" signal "TOP")
		(4 "In1.Cu" signal "GND")
		(6 "In2.Cu" signal "IN1")
		(8 "In3.Cu" signal "GND1")
		(10 "In4.Cu" signal "IN2")
		(12 "In5.Cu" signal "GND2")
		(14 "In6.Cu" signal "IN3")
		(16 "In7.Cu" signal "GND3")
		(18 "In8.Cu" signal "VCC")
		(20 "In9.Cu" signal "VCC1")
		(22 "In10.Cu" signal "GND4")
		(24 "In11.Cu" signal "IN4")
		(26 "In12.Cu" signal "GND5")
		(28 "In13.Cu" signal "IN5")
		(30 "In14.Cu" signal "GND6")
		(32 "In15.Cu" signal "IN6")
		(34 "In16.Cu" signal "GND7")
		(2 "B.Cu" signal "BOTTOM")
		(9 "F.Adhes" user "F.Adhesive")
		(11 "B.Adhes" user "B.Adhesive")
		(13 "F.Paste" user "Package Geometry/Pastemask Top")
		(15 "B.Paste" user "Package Geometry/Pastemask Bottom")
		(5 "F.SilkS" user "Ref Des/Silkscreen Top")
		(7 "B.SilkS" user "Ref Des/Silkscreen Bottom")
		(1 "F.Mask" user "Board Geometry/Soldermask Top")
		(3 "B.Mask" user "Board Geometry/Soldermask Bottom")
		(17 "Dwgs.User" user "User.Drawings")
		(19 "Cmts.User" user "User.Comments")
		(21 "Eco1.User" user "User.Eco1")
		(23 "Eco2.User" user "User.Eco2")
		(25 "Edge.Cuts" user "Board Geometry/Outline")
		(27 "Margin" user)
		(31 "F.CrtYd" user "Package Geometry/Place Bound Top")
		(29 "B.CrtYd" user "Package Geometry/Place Bound Bottom")
		(35 "F.Fab" user "Ref Des/Assembly Top")
		(33 "B.Fab" user "Ref Des/Assembly Bottom")
	)
	(footprint ""
		(layer "B.Cu")
		(at 67.201034 -199.336152)
		(property "Reference" "R553"
			(at 0 0 0)
			(layer "B.SilkS")
			(hide yes)
			(effects
				(font
					(size 1.27 1.27)
				)
				(justify mirror)
			)
		)
		(property "Value" ""
			(at 0 0 0)
			(layer "B.Fab")
			(effects
				(font
					(size 1.27 1.27)
				)
				(justify mirror)
			)
		)
		(duplicate_pad_numbers_are_jumpers no)
		(fp_line
			(start -0.7874 -0.4064)
			(end -0.7874 0.4064)
			(stroke
				(width 0.1524)
				(type default)
			)
			(layer "B.SilkS")
		)
		(fp_line
			(start -0.7874 0.4064)
			(end 0.7874 0.4064)
			(stroke
				(width 0.1524)
				(type default)
			)
			(layer "B.SilkS")
		)
		(fp_line
			(start 0.7874 -0.4064)
			(end -0.7874 -0.4064)
			(stroke
				(width 0.1524)
				(type default)
			)
			(layer "B.SilkS")
		)
		(fp_line
			(start 0.7874 0.4064)
			(end 0.7874 -0.4064)
			(stroke
				(width 0.1524)
				(type default)
			)
			(layer "B.SilkS")
		)
		(fp_line
			(start -0.67945 -0.3048)
			(end -0.67945 0.3048)
			(stroke
				(width 0.1)
				(type default)
			)
			(layer "B.Fab")
		)
		(fp_line
			(start -0.67945 0.3048)
			(end -0.120396 0.3048)
			(stroke
				(width 0.1)
				(type default)
			)
			(layer "B.Fab")
		)
		(fp_line
			(start -0.12065 -0.3048)
			(end -0.67945 -0.3048)
			(stroke
				(width 0.1)
				(type default)
			)
			(layer "B.Fab")
		)
		(fp_line
			(start -0.12065 -0.2794)
			(end -0.12065 -0.3048)
			(stroke
				(width 0.1)
				(type default)
			)
			(layer "B.Fab")
		)
		(fp_line
			(start -0.120396 0.2794)
			(end 0.12065 0.2794)
			(stroke
				(width 0.1)
				(type default)
			)
			(layer "B.Fab")
		)
		(fp_line
			(start -0.120396 0.3048)
			(end -0.120396 0.2794)
			(stroke
				(width 0.1)
				(type default)
			)
			(layer "B.Fab")
		)
		(fp_line
			(start 0.12065 -0.305054)
			(end 0.12065 -0.2794)
			(stroke
				(width 0.1)
				(type default)
			)
			(layer "B.Fab")
		)
		(fp_line
			(start 0.12065 -0.2794)
			(end -0.12065 -0.2794)
			(stroke
				(width 0.1)
				(type default)
			)
			(layer "B.Fab")
		)
		(fp_line
			(start 0.12065 0.2794)
			(end 0.12065 0.3048)
			(stroke
				(width 0.1)
				(type default)
			)
			(layer "B.Fab")
		)
		(fp_line
			(start 0.12065 0.3048)
			(end 0.67945 0.3048)
			(stroke
				(width 0.1)
				(type default)
			)
			(layer "B.Fab")
		)
		(fp_line
			(start 0.67945 -0.305054)
			(end 0.12065 -0.305054)
			(stroke
				(width 0.1)
				(type default)
			)
			(layer "B.Fab")
		)
		(fp_line
			(start 0.67945 0.3048)
			(end 0.67945 -0.305054)
			(stroke
				(width 0.1)
				(type default)
			)
			(layer "B.Fab")
		)
		(pad "1" smd circle
			(at 0.40005 0 180)
			(size 0 0)
			(layers "B.Cu" "B.Mask" "B.Paste")
			(net "CPU1_NV_SAVE_N")
		)
		(pad "2" smd circle
			(at -0.40005 0 180)
			(size 0 0)
			(layers "B.Cu" "B.Mask" "B.Paste")
			(net "PVDD18_S5_P1")
		)
	)
	(footprint ""
		(layer "B.Cu")
		(at 92.185744 -408.517344 90)
		(property "Reference" "C6690"
			(at 0 0 90)
			(layer "B.SilkS")
			(hide yes)
			(effects
				(font
					(size 1.27 1.27)
				)
				(justify mirror)
			)
		)
		(property "Value" ""
			(at 0 0 90)
			(layer "B.Fab")
			(effects
				(font
					(size 1.27 1.27)
				)
				(justify mirror)
			)
		)
		(duplicate_pad_numbers_are_jumpers no)
		(fp_line
			(start 0.299974 -0.150114)
			(end -0.299974 -0.150114)
			(stroke
				(width 0.1)
				(type default)
			)
			(layer "B.Fab")
		)
		(fp_line
			(start -0.299974 -0.150114)
			(end -0.299974 0.150114)
			(stroke
				(width 0.1)
				(type default)
			)
			(layer "B.Fab")
		)
		(fp_line
			(start 0.299974 0.150114)
			(end 0.299974 -0.150114)
			(stroke
				(width 0.1)
				(type default)
			)
			(layer "B.Fab")
		)
		(fp_line
			(start -0.299974 0.150114)
			(end 0.299974 0.150114)
			(stroke
				(width 0.1)
				(type default)
			)
			(layer "B.Fab")
		)
		(pad "1" smd rect
			(at 0.2667 0 270)
			(size 0.3048 0.381)
			(layers "B.Cu" "B.Mask" "B.Paste")
			(net "P5E_CPU1_P1_TX_BUF_C_DN<14>")
		)
		(pad "2" smd rect
			(at -0.2667 0 270)
			(size 0.3048 0.381)
			(layers "B.Cu" "B.Mask" "B.Paste")
			(net "P5E_CPU1_P1_TX_BUF_DN<14>")
		)
	)
	(footprint ""
		(layer "B.Cu")
		(at 340.718902 -398.942052 90)
		(property "Reference" "C630"
			(at 0 0 90)
			(layer "B.SilkS")
			(hide yes)
			(effects
				(font
					(size 1.27 1.27)
				)
				(justify mirror)
			)
		)
		(property "Value" ""
			(at 0 0 90)
			(layer "B.Fab")
			(effects
				(font
					(size 1.27 1.27)
				)
				(justify mirror)
			)
		)
		(duplicate_pad_numbers_are_jumpers no)
		(fp_line
			(start 0.7874 -0.4064)
			(end -0.7874 -0.4064)
			(stroke
				(width 0.1524)
				(type default)
			)
			(layer "B.SilkS")
		)
		(fp_line
			(start -0.7874 -0.4064)
			(end -0.7874 0.4064)
			(stroke
				(width 0.1524)
				(type default)
			)
			(layer "B.SilkS")
		)
		(fp_line
			(start 0.7874 0.4064)
			(end 0.7874 -0.4064)
			(stroke
				(width 0.1524)
				(type default)
			)
			(layer "B.SilkS")
		)
		(fp_line
			(start -0.7874 0.4064)
			(end 0.7874 0.4064)
			(stroke
				(width 0.1524)
				(type default)
			)
			(layer "B.SilkS")
		)
		(fp_line
			(start 0.67945 -0.305054)
			(end 0.12065 -0.305054)
			(stroke
				(width 0.1)
				(type default)
			)
			(layer "B.Fab")
		)
		(fp_line
			(start 0.12065 -0.305054)
			(end 0.12065 -0.2794)
			(stroke
				(width 0.1)
				(type default)
			)
			(layer "B.Fab")
		)
		(fp_line
			(start -0.12065 -0.3048)
			(end -0.67945 -0.3048)
			(stroke
				(width 0.1)
				(type default)
			)
			(layer "B.Fab")
		)
		(fp_line
			(start -0.67945 -0.3048)
			(end -0.67945 0.3048)
			(stroke
				(width 0.1)
				(type default)
			)
			(layer "B.Fab")
		)
		(fp_line
			(start 0.12065 -0.2794)
			(end -0.12065 -0.2794)
			(stroke
				(width 0.1)
				(type default)
			)
			(layer "B.Fab")
		)
		(fp_line
			(start -0.12065 -0.2794)
			(end -0.12065 -0.3048)
			(stroke
				(width 0.1)
				(type default)
			)
			(layer "B.Fab")
		)
		(fp_line
			(start 0.12065 0.2794)
			(end 0.12065 0.3048)
			(stroke
				(width 0.1)
				(type default)
			)
			(layer "B.Fab")
		)
		(fp_line
			(start -0.120396 0.2794)
			(end 0.12065 0.2794)
			(stroke
				(width 0.1)
				(type default)
			)
			(layer "B.Fab")
		)
		(fp_line
			(start 0.67945 0.3048)
			(end 0.67945 -0.305054)
			(stroke
				(width 0.1)
				(type default)
			)
			(layer "B.Fab")
		)
		(fp_line
			(start 0.12065 0.3048)
			(end 0.67945 0.3048)
			(stroke
				(width 0.1)
				(type default)
			)
			(layer "B.Fab")
		)
		(fp_line
			(start -0.120396 0.3048)
			(end -0.120396 0.2794)
			(stroke
				(width 0.1)
				(type default)
			)
			(layer "B.Fab")
		)
		(fp_line
			(start -0.67945 0.3048)
			(end -0.120396 0.3048)
			(stroke
				(width 0.1)
				(type default)
			)
			(layer "B.Fab")
		)
		(pad "1" smd circle
			(at 0.40005 0 270)
			(size 0 0)
			(layers "B.Cu" "B.Mask" "B.Paste")
			(net "P0V9_CPU0_RT1_2A")
		)
		(pad "2" smd circle
			(at -0.40005 0 270)
			(size 0 0)
			(layers "B.Cu" "B.Mask" "B.Paste")
			(net "GND")
		)
	)
)
